(kicad_pcb
	(version 20260206)
	(generator "pcbnew")
	(generator_version "10.0")
	(general
		(thickness 1.6)
		(legacy_teardrops no)
	)
	(paper "A4")
	(title_block
		(title "Wiwynn_Tioga_Pass_MB.brd")
		(comment 1 "Tioga Pass / footprints 911-917 of 4770")
	)
	(layers
		(0 "F.Cu" signal "TOP")
		(4 "In1.Cu" signal "L2GND")
		(6 "In2.Cu" signal "L3")
		(8 "In3.Cu" signal "L4GND")
		(10 "In4.Cu" signal "L5")
		(12 "In5.Cu" signal "L6GND")
		(14 "In6.Cu" signal "L7VCC")
		(16 "In7.Cu" signal "L8VCC")
		(18 "In8.Cu" signal "L9GND")
		(20 "In9.Cu" signal "L10")
		(22 "In10.Cu" signal "L11GND")
		(24 "In11.Cu" signal "L12")
		(26 "In12.Cu" signal "L13GND")
		(2 "B.Cu" signal "BOTTOM")
		(9 "F.Adhes" user "F.Adhesive")
		(11 "B.Adhes" user "B.Adhesive")
		(13 "F.Paste" user "Package Geometry/Pastemask Top")
		(15 "B.Paste" user "Package Geometry/Pastemask Bottom")
		(5 "F.SilkS" user "Ref Des/Silkscreen Top")
		(7 "B.SilkS" user "Ref Des/Silkscreen Bottom")
		(1 "F.Mask" user "Board Geometry/Soldermask Top")
		(3 "B.Mask" user "Board Geometry/Soldermask Bottom")
		(17 "Dwgs.User" user "User.Drawings")
		(19 "Cmts.User" user "User.Comments")
		(21 "Eco1.User" user "User.Eco1")
		(23 "Eco2.User" user "User.Eco2")
		(25 "Edge.Cuts" user "Board Geometry/Outline")
		(27 "Margin" user)
		(31 "F.CrtYd" user "Package Geometry/Place Bound Top")
		(29 "B.CrtYd" user "Package Geometry/Place Bound Bottom")
		(35 "F.Fab" user "Ref Des/Assembly Top")
		(33 "B.Fab" user "Ref Des/Assembly Bottom")
	)
	(footprint ""
		(layer "F.Cu")
		(at 40.036496 -57.031382)
		(property "Reference" "L1E1"
			(at 3.378708 -4.251706 0)
			(unlocked yes)
			(layer "F.SilkS")
			(effects
				(font
					(size 0.4064 0.254)
					(thickness 0.1524)
				)
			)
		)
		(property "Value" ""
			(at 0 0 0)
			(layer "F.Fab")
			(effects
				(font
					(size 1.27 1.27)
				)
			)
		)
		(duplicate_pad_numbers_are_jumpers no)
		(fp_line
			(start -1.1303 -3.199892)
			(end 8.3693 -3.199892)
			(stroke
				(width 0.1524)
				(type default)
			)
			(layer "F.SilkS")
		)
		(fp_line
			(start -1.1303 -1.6637)
			(end -1.1303 -3.199892)
			(stroke
				(width 0.1524)
				(type default)
			)
			(layer "F.SilkS")
		)
		(fp_line
			(start -1.1303 3.199892)
			(end -1.1303 1.6637)
			(stroke
				(width 0.1524)
				(type default)
			)
			(layer "F.SilkS")
		)
		(fp_line
			(start 8.3693 -3.199892)
			(end 8.3693 -1.6637)
			(stroke
				(width 0.1524)
				(type default)
			)
			(layer "F.SilkS")
		)
		(fp_line
			(start 8.3693 1.6637)
			(end 8.3693 3.199892)
			(stroke
				(width 0.1524)
				(type default)
			)
			(layer "F.SilkS")
		)
		(fp_line
			(start 8.3693 3.199892)
			(end -1.1303 3.199892)
			(stroke
				(width 0.1524)
				(type default)
			)
			(layer "F.SilkS")
		)
		(fp_rect
			(start -1.1303 3.199892)
			(end 8.3693 -3.199892)
			(stroke
				(width 0)
				(type default)
			)
			(fill no)
			(layer "F.CrtYd")
		)
		(fp_line
			(start -1.1303 -3.199892)
			(end 8.3693 -3.199892)
			(stroke
				(width 0.1)
				(type default)
			)
			(layer "F.Fab")
		)
		(fp_line
			(start -1.1303 3.199892)
			(end -1.1303 -3.199892)
			(stroke
				(width 0.1)
				(type default)
			)
			(layer "F.Fab")
		)
		(fp_line
			(start 8.3693 -3.199892)
			(end 8.3693 3.199892)
			(stroke
				(width 0.1)
				(type default)
			)
			(layer "F.Fab")
		)
		(fp_line
			(start 8.3693 3.199892)
			(end -1.1303 3.199892)
			(stroke
				(width 0.1)
				(type default)
			)
			(layer "F.Fab")
		)
		(pad "1" smd rect
			(at 0 0)
			(size 3.683 2.667)
			(layers "F.Cu" "F.Mask" "F.Paste")
			(net "VR_PVCCIN_CPU1_PHASE1")
		)
		(pad "2" smd rect
			(at 7.239 0)
			(size 3.683 2.667)
			(layers "F.Cu" "F.Mask" "F.Paste")
			(net "PVCCIN_CPU1")
		)
	)
	(footprint ""
		(layer "F.Cu")
		(at 172.466 -86.868 180)
		(property "Reference" "R4D7"
			(at 0 0 180)
			(layer "F.SilkS")
			(hide yes)
			(effects
				(font
					(size 1.27 1.27)
				)
			)
		)
		(property "Value" ""
			(at 0 0 180)
			(layer "F.Fab")
			(effects
				(font
					(size 1.27 1.27)
				)
			)
		)
		(duplicate_pad_numbers_are_jumpers no)
		(fp_poly
			(pts
				(xy -0.2794 -0.1016) (xy 0.2794 -0.1016) (xy 0.2794 0.9906) (xy -0.2794 0.9906)
			)
			(stroke
				(width 0)
				(type default)
			)
			(fill no)
			(layer "F.CrtYd")
		)
		(fp_line
			(start 0.2794 0.9906)
			(end 0.2794 -0.1016)
			(stroke
				(width 0.1)
				(type default)
			)
			(layer "F.Fab")
		)
		(fp_line
			(start 0.2794 -0.1016)
			(end -0.2794 -0.1016)
			(stroke
				(width 0.1)
				(type default)
			)
			(layer "F.Fab")
		)
		(fp_line
			(start -0.2794 0.9906)
			(end 0.2794 0.9906)
			(stroke
				(width 0.1)
				(type default)
			)
			(layer "F.Fab")
		)
		(fp_line
			(start -0.2794 -0.1016)
			(end -0.2794 0.9906)
			(stroke
				(width 0.1)
				(type default)
			)
			(layer "F.Fab")
		)
		(pad "1" smd rect
			(at 0 0 180)
			(size 0.508 0.508)
			(layers "F.Cu" "F.Mask" "F.Paste")
			(net "CLK_100M_CPU0_RC_REFCLK0_R_DN")
		)
		(pad "2" smd rect
			(at 0 0.889 180)
			(size 0.508 0.508)
			(layers "F.Cu" "F.Mask" "F.Paste")
			(net "CLK_100M_CPU0_RC_REFCLK0_DN")
		)
		(zone
			(layer "F.Cu")
			(hatch none 0.5)
			(connect_pads
				(clearance 0)
			)
			(min_thickness 0.25)
			(keepout
				(tracks not_allowed)
				(vias allowed)
				(pads allowed)
				(copperpour not_allowed)
				(footprints allowed)
			)
			(placement
				(enabled no)
				(sheetname "")
			)
			(fill
				(thermal_gap 0.5)
				(thermal_bridge_width 0.5)
				(island_removal_mode 0)
			)
			(polygon
				(pts
					(xy 172.72 -87.503) (xy 172.212 -87.503) (xy 172.212 -87.122) (xy 172.72 -87.122)
				)
			)
		)
		(zone
			(layer "F.Cu")
			(hatch none 0.5)
			(connect_pads
				(clearance 0)
			)
			(min_thickness 0.25)
			(keepout
				(tracks allowed)
				(vias not_allowed)
				(pads allowed)
				(copperpour not_allowed)
				(footprints allowed)
			)
			(placement
				(enabled no)
				(sheetname "")
			)
			(fill
				(thermal_gap 0.5)
				(thermal_bridge_width 0.5)
				(island_removal_mode 0)
			)
			(polygon
				(pts
					(xy 172.72 -87.122) (xy 172.212 -87.122) (xy 172.212 -87.503) (xy 172.72 -87.503)
				)
			)
		)
	)
	(footprint ""
		(layer "F.Cu")
		(at 369.062 -96.8375)
		(property "Reference" "C7C15"
			(at 0 0 0)
			(layer "F.SilkS")
			(hide yes)
			(effects
				(font
					(size 1.27 1.27)
				)
			)
		)
		(property "Value" ""
			(at 0 0 0)
			(layer "F.Fab")
			(effects
				(font
					(size 1.27 1.27)
				)
			)
		)
		(duplicate_pad_numbers_are_jumpers no)
		(fp_poly
			(pts
				(xy 0.3048 -0.1016) (xy 0.3048 0.9906) (xy -0.3048 0.9906) (xy -0.3048 -0.1016)
			)
			(stroke
				(width 0)
				(type default)
			)
			(fill no)
			(layer "F.CrtYd")
		)
		(fp_line
			(start -0.3048 -0.1016)
			(end -0.3048 0.9906)
			(stroke
				(width 0.1)
				(type default)
			)
			(layer "F.Fab")
		)
		(fp_line
			(start -0.3048 0.9906)
			(end 0.3048 0.9906)
			(stroke
				(width 0.1)
				(type default)
			)
			(layer "F.Fab")
		)
		(fp_line
			(start 0.3048 -0.1016)
			(end -0.3048 -0.1016)
			(stroke
				(width 0.1)
				(type default)
			)
			(layer "F.Fab")
		)
		(fp_line
			(start 0.3048 0.9906)
			(end 0.3048 -0.1016)
			(stroke
				(width 0.1)
				(type default)
			)
			(layer "F.Fab")
		)
		(pad "1" smd rect
			(at 0 0)
			(size 0.508 0.508)
			(layers "F.Cu" "F.Mask" "F.Paste")
			(net "XTAL_33K_RTC2")
		)
		(pad "2" smd rect
			(at 0 0.889)
			(size 0.508 0.508)
			(layers "F.Cu" "F.Mask" "F.Paste")
			(net "GND")
		)
		(zone
			(layer "F.Cu")
			(hatch none 0.5)
			(connect_pads
				(clearance 0)
			)
			(min_thickness 0.25)
			(keepout
				(tracks allowed)
				(vias not_allowed)
				(pads allowed)
				(copperpour not_allowed)
				(footprints allowed)
			)
			(placement
				(enabled no)
				(sheetname "")
			)
			(fill
				(thermal_gap 0.5)
				(thermal_bridge_width 0.5)
				(island_removal_mode 0)
			)
			(polygon
				(pts
					(xy 368.808 -96.5835) (xy 369.316 -96.5835) (xy 369.316 -96.2025) (xy 368.808 -96.2025)
				)
			)
		)
		(zone
			(layer "F.Cu")
			(hatch none 0.5)
			(connect_pads
				(clearance 0)
			)
			(min_thickness 0.25)
			(keepout
				(tracks not_allowed)
				(vias allowed)
				(pads allowed)
				(copperpour not_allowed)
				(footprints allowed)
			)
			(placement
				(enabled no)
				(sheetname "")
			)
			(fill
				(thermal_gap 0.5)
				(thermal_bridge_width 0.5)
				(island_removal_mode 0)
			)
			(polygon
				(pts
					(xy 368.808 -96.2025) (xy 369.316 -96.2025) (xy 369.316 -96.5835) (xy 368.808 -96.5835)
				)
			)
		)
	)
	(footprint ""
		(layer "F.Cu")
		(at 13.7541 -152.3111 -90)
		(property "Reference" "C1A1"
			(at 0 0 270)
			(layer "F.SilkS")
			(hide yes)
			(effects
				(font
					(size 1.27 1.27)
				)
			)
		)
		(property "Value" ""
			(at 0 0 270)
			(layer "F.Fab")
			(effects
				(font
					(size 1.27 1.27)
				)
			)
		)
		(duplicate_pad_numbers_are_jumpers no)
		(fp_poly
			(pts
				(xy -0.7239 -0.2159) (xy 0.7239 -0.2159) (xy 0.7239 1.9939) (xy -0.7239 1.9939)
			)
			(stroke
				(width 0)
				(type default)
			)
			(fill no)
			(layer "F.CrtYd")
		)
		(fp_line
			(start -0.7239 1.9939)
			(end 0.7239 1.9939)
			(stroke
				(width 0.1)
				(type default)
			)
			(layer "F.Fab")
		)
		(fp_line
			(start 0.7239 1.9939)
			(end 0.7239 -0.2159)
			(stroke
				(width 0.1)
				(type default)
			)
			(layer "F.Fab")
		)
		(fp_line
			(start -0.7239 -0.2159)
			(end -0.7239 1.9939)
			(stroke
				(width 0.1)
				(type default)
			)
			(layer "F.Fab")
		)
		(fp_line
			(start 0.7239 -0.2159)
			(end -0.7239 -0.2159)
			(stroke
				(width 0.1)
				(type default)
			)
			(layer "F.Fab")
		)
		(pad "1" smd rect
			(at 0 0 270)
			(size 1.27 1.016)
			(layers "F.Cu" "F.Mask" "F.Paste")
			(net "PVDDQ_KLM")
		)
		(pad "2" smd rect
			(at 0 1.778 270)
			(size 1.27 1.016)
			(layers "F.Cu" "F.Mask" "F.Paste")
			(net "GND")
		)
		(zone
			(layer "F.Cu")
			(hatch none 0.5)
			(connect_pads
				(clearance 0)
			)
			(min_thickness 0.25)
			(keepout
				(tracks not_allowed)
				(vias allowed)
				(pads allowed)
				(copperpour not_allowed)
				(footprints allowed)
			)
			(placement
				(enabled no)
				(sheetname "")
			)
			(fill
				(thermal_gap 0.5)
				(thermal_bridge_width 0.5)
				(island_removal_mode 0)
			)
			(polygon
				(pts
					(xy 13.2461 -152.9461) (xy 13.2461 -151.6761) (xy 12.4841 -151.6761) (xy 12.4841 -152.9461)
				)
			)
		)
	)
	(footprint ""
		(layer "F.Cu")
		(at 382.131062 -76.019406 180)
		(property "Reference" "R2T44"
			(at 0 0 180)
			(layer "F.SilkS")
			(hide yes)
			(effects
				(font
					(size 1.27 1.27)
				)
			)
		)
		(property "Value" ""
			(at 0 0 180)
			(layer "F.Fab")
			(effects
				(font
					(size 1.27 1.27)
				)
			)
		)
		(duplicate_pad_numbers_are_jumpers no)
		(fp_poly
			(pts
				(xy -0.2794 -0.1016) (xy 0.2794 -0.1016) (xy 0.2794 0.9906) (xy -0.2794 0.9906)
			)
			(stroke
				(width 0)
				(type default)
			)
			(fill no)
			(layer "F.CrtYd")
		)
		(fp_line
			(start 0.2794 0.9906)
			(end 0.2794 -0.1016)
			(stroke
				(width 0.1)
				(type default)
			)
			(layer "F.Fab")
		)
		(fp_line
			(start 0.2794 -0.1016)
			(end -0.2794 -0.1016)
			(stroke
				(width 0.1)
				(type default)
			)
			(layer "F.Fab")
		)
		(fp_line
			(start -0.2794 0.9906)
			(end 0.2794 0.9906)
			(stroke
				(width 0.1)
				(type default)
			)
			(layer "F.Fab")
		)
		(fp_line
			(start -0.2794 -0.1016)
			(end -0.2794 0.9906)
			(stroke
				(width 0.1)
				(type default)
			)
			(layer "F.Fab")
		)
		(pad "1" smd rect
			(at 0 0 180)
			(size 0.508 0.508)
			(layers "F.Cu" "F.Mask" "F.Paste")
			(net "H_CPU1_ERR2_G_N")
		)
		(pad "2" smd rect
			(at 0 0.889 180)
			(size 0.508 0.508)
			(layers "F.Cu" "F.Mask" "F.Paste")
			(net "H_CPU_ERR2_G_R_N")
		)
		(zone
			(layer "F.Cu")
			(hatch none 0.5)
			(connect_pads
				(clearance 0)
			)
			(min_thickness 0.25)
			(keepout
				(tracks not_allowed)
				(vias allowed)
				(pads allowed)
				(copperpour not_allowed)
				(footprints allowed)
			)
			(placement
				(enabled no)
				(sheetname "")
			)
			(fill
				(thermal_gap 0.5)
				(thermal_bridge_width 0.5)
				(island_removal_mode 0)
			)
			(polygon
				(pts
					(xy 382.385062 -76.654406) (xy 381.877062 -76.654406) (xy 381.877062 -76.273406) (xy 382.385062 -76.273406)
				)
			)
		)
		(zone
			(layer "F.Cu")
			(hatch none 0.5)
			(connect_pads
				(clearance 0)
			)
			(min_thickness 0.25)
			(keepout
				(tracks allowed)
				(vias not_allowed)
				(pads allowed)
				(copperpour not_allowed)
				(footprints allowed)
			)
			(placement
				(enabled no)
				(sheetname "")
			)
			(fill
				(thermal_gap 0.5)
				(thermal_bridge_width 0.5)
				(island_removal_mode 0)
			)
			(polygon
				(pts
					(xy 382.385062 -76.273406) (xy 381.877062 -76.273406) (xy 381.877062 -76.654406) (xy 382.385062 -76.654406)
				)
			)
		)
	)
	(footprint ""
		(layer "F.Cu")
		(at 349.2246 -149.112224 90)
		(property "Reference" "C7A24"
			(at 0 0 90)
			(layer "F.SilkS")
			(hide yes)
			(effects
				(font
					(size 1.27 1.27)
				)
			)
		)
		(property "Value" ""
			(at 0 0 90)
			(layer "F.Fab")
			(effects
				(font
					(size 1.27 1.27)
				)
			)
		)
		(duplicate_pad_numbers_are_jumpers no)
		(fp_poly
			(pts
				(xy 0.3048 -0.1016) (xy 0.3048 0.9906) (xy -0.3048 0.9906) (xy -0.3048 -0.1016)
			)
			(stroke
				(width 0)
				(type default)
			)
			(fill no)
			(layer "F.CrtYd")
		)
		(fp_line
			(start 0.3048 -0.1016)
			(end -0.3048 -0.1016)
			(stroke
				(width 0.1)
				(type default)
			)
			(layer "F.Fab")
		)
		(fp_line
			(start -0.3048 -0.1016)
			(end -0.3048 0.9906)
			(stroke
				(width 0.1)
				(type default)
			)
			(layer "F.Fab")
		)
		(fp_line
			(start 0.3048 0.9906)
			(end 0.3048 -0.1016)
			(stroke
				(width 0.1)
				(type default)
			)
			(layer "F.Fab")
		)
		(fp_line
			(start -0.3048 0.9906)
			(end 0.3048 0.9906)
			(stroke
				(width 0.1)
				(type default)
			)
			(layer "F.Fab")
		)
		(pad "1" smd rect
			(at 0 0 90)
			(size 0.508 0.508)
			(layers "F.Cu" "F.Mask" "F.Paste")
			(net "VR_PVDDQ_DEF_PH2_VCIN")
		)
		(pad "2" smd rect
			(at 0 0.889 90)
			(size 0.508 0.508)
			(layers "F.Cu" "F.Mask" "F.Paste")
			(net "GND")
		)
		(zone
			(layer "F.Cu")
			(hatch none 0.5)
			(connect_pads
				(clearance 0)
			)
			(min_thickness 0.25)
			(keepout
				(tracks allowed)
				(vias not_allowed)
				(pads allowed)
				(copperpour not_allowed)
				(footprints allowed)
			)
			(placement
				(enabled no)
				(sheetname "")
			)
			(fill
				(thermal_gap 0.5)
				(thermal_bridge_width 0.5)
				(island_removal_mode 0)
			)
			(polygon
				(pts
					(xy 349.4786 -148.858224) (xy 349.4786 -149.366224) (xy 349.8596 -149.366224) (xy 349.8596 -148.858224)
				)
			)
		)
		(zone
			(layer "F.Cu")
			(hatch none 0.5)
			(connect_pads
				(clearance 0)
			)
			(min_thickness 0.25)
			(keepout
				(tracks not_allowed)
				(vias allowed)
				(pads allowed)
				(copperpour not_allowed)
				(footprints allowed)
			)
			(placement
				(enabled no)
				(sheetname "")
			)
			(fill
				(thermal_gap 0.5)
				(thermal_bridge_width 0.5)
				(island_removal_mode 0)
			)
			(polygon
				(pts
					(xy 349.8596 -148.858224) (xy 349.8596 -149.366224) (xy 349.4786 -149.366224) (xy 349.4786 -148.858224)
				)
			)
		)
	)
	(footprint ""
		(layer "F.Cu")
		(at 108.9025 -164.973 -90)
		(property "Reference" "T1D7"
			(at 0 0 270)
			(layer "F.SilkS")
			(hide yes)
			(effects
				(font
					(size 1.27 1.27)
				)
			)
		)
		(property "Value" "*"
			(at -3.4036 -4.46405 270)
			(unlocked yes)
			(layer "F.Fab")
			(hide yes)
			(effects
				(font
					(size 0.889 0.889)
					(thickness 0.1524)
				)
			)
		)
		(property "Device Type" "TEST-PAD-12P-1-GP-U_DISCRET-GBA"
			(at -3.4036 -5.98805 270)
			(unlocked yes)
			(layer "F.Fab")
			(hide yes)
			(effects
				(font
					(size 0.889 0.889)
					(thickness 0.1524)
				)
			)
		)
		(duplicate_pad_numbers_are_jumpers no)
		(fp_line
			(start -2.3876 3.4798)
			(end -2.3876 -4.826)
			(stroke
				(width 0.1524)
				(type default)
			)
			(layer "F.SilkS")
		)
		(fp_line
			(start 2.3622 3.4798)
			(end -2.3876 3.4798)
			(stroke
				(width 0.1524)
				(type default)
			)
			(layer "F.SilkS")
		)
		(fp_line
			(start -2.3876 -4.826)
			(end 2.3622 -4.826)
			(stroke
				(width 0.1524)
				(type default)
			)
			(layer "F.SilkS")
		)
		(fp_line
			(start 2.3622 -4.826)
			(end 2.3622 3.4798)
			(stroke
				(width 0.1524)
				(type default)
			)
			(layer "F.SilkS")
		)
		(fp_rect
			(start -2.6416 3.7338)
			(end 2.6162 -5.08)
			(stroke
				(width 0)
				(type default)
			)
			(fill no)
			(layer "F.CrtYd")
		)
		(fp_rect
			(start -2.6416 3.7338)
			(end 2.6162 -5.08)
			(stroke
				(width 0)
				(type default)
			)
			(fill no)
			(layer "F.Fab")
		)
		(pad "1" smd circle
			(at 0.496824 -1.301496 270)
			(size 0.6604 0.6604)
			(layers "F.Cu" "F.Mask" "F.Paste")
			(net "L10_85OHM_5INCH_DP")
		)
		(pad "2" smd circle
			(at -0.503936 -1.301496 270)
			(size 0.6604 0.6604)
			(layers "F.Cu" "F.Mask" "F.Paste")
			(net "L10_85OHM_5INCH_DN")
		)
		(pad "3" smd custom
			(at -0.00889 0.370078 270)
			(size 0.74295 0.74295)
			(layers "F.Cu" "F.Mask" "F.Paste")
			(net "GND")
			(options
				(clearance outline)
				(anchor circle)
			)
			(primitives
				(gr_poly
					(pts
						(xy -2.1209 1.4859) (xy 2.1209 1.4859) (xy 2.1209 -1.4859) (xy 1.08585 -1.4859) (xy 1.08585 -0.4699)
						(xy -1.08585 -0.4699) (xy -1.08585 -1.4859) (xy -2.1209 -1.4859)
					)
					(width 0)
					(fill yes)
				)
			)
		)
		(pad "4" thru_hole circle
			(at 1.266444 -3.851656 270)
			(size 1.4478 1.4478)
			(drill 1.0414)
			(layers "*.Cu" "*.Mask")
			(remove_unused_layers no)
			(net "GND")
			(clearance 0.1524)
			(thermal_gap 0.1524)
		)
		(pad "5" thru_hole circle
			(at -1.273556 -3.851656 270)
			(size 1.4478 1.4478)
			(drill 1.0414)
			(layers "*.Cu" "*.Mask")
			(remove_unused_layers no)
			(net "GND")
			(clearance 0.1524)
			(thermal_gap 0.1524)
		)
		(pad "6" thru_hole circle
			(at 1.266444 2.498344 270)
			(size 1.4478 1.4478)
			(drill 1.0414)
			(layers "*.Cu" "*.Mask")
			(remove_unused_layers no)
			(net "GND")
			(clearance 0.1524)
			(thermal_gap 0.1524)
		)
		(pad "7" thru_hole circle
			(at -1.273556 2.498344 270)
			(size 1.4478 1.4478)
			(drill 1.0414)
			(layers "*.Cu" "*.Mask")
			(remove_unused_layers no)
			(net "GND")
			(clearance 0.1524)
			(thermal_gap 0.1524)
		)
		(pad "8" thru_hole circle
			(at 1.27 -0.4572 270)
			(size 0.7112 0.7112)
			(drill 0.4064)
			(layers "*.Cu" "*.Mask")
			(remove_unused_layers no)
			(net "GND")
			(clearance 0.1016)
			(thermal_gap 0.1016)
		)
		(pad "9" thru_hole circle
			(at 1.27 0.762 270)
			(size 0.7112 0.7112)
			(drill 0.4064)
			(layers "*.Cu" "*.Mask")
			(remove_unused_layers no)
			(net "GND")
			(clearance 0.1016)
			(thermal_gap 0.1016)
		)
		(pad "10" thru_hole circle
			(at -0.0254 0.762 270)
			(size 0.7112 0.7112)
			(drill 0.4064)
			(layers "*.Cu" "*.Mask")
			(remove_unused_layers no)
			(net "GND")
			(clearance 0.1016)
			(thermal_gap 0.1016)
		)
		(pad "11" thru_hole circle
			(at -1.27 0.762 270)
			(size 0.7112 0.7112)
			(drill 0.4064)
			(layers "*.Cu" "*.Mask")
			(remove_unused_layers no)
			(net "GND")
			(clearance 0.1016)
			(thermal_gap 0.1016)
		)
		(pad "12" thru_hole circle
			(at -1.27 -0.4572 270)
			(size 0.7112 0.7112)
			(drill 0.4064)
			(layers "*.Cu" "*.Mask")
			(remove_unused_layers no)
			(net "GND")
			(clearance 0.1016)
			(thermal_gap 0.1016)
		)
	)
)
